(kicad_pcb
	(version 20260206)
	(generator "pcbnew")
	(generator_version "10.0")
	(general
		(thickness 1.6)
		(legacy_teardrops no)
	)
	(paper "A4")
	(title_block
		(title "Wiwynn_Tioga_Pass_MB.brd")
		(comment 1 "Tioga Pass / footprints 2432-2439 of 4770")
	)
	(layers
		(0 "F.Cu" signal "TOP")
		(4 "In1.Cu" signal "L2GND")
		(6 "In2.Cu" signal "L3")
		(8 "In3.Cu" signal "L4GND")
		(10 "In4.Cu" signal "L5")
		(12 "In5.Cu" signal "L6GND")
		(14 "In6.Cu" signal "L7VCC")
		(16 "In7.Cu" signal "L8VCC")
		(18 "In8.Cu" signal "L9GND")
		(20 "In9.Cu" signal "L10")
		(22 "In10.Cu" signal "L11GND")
		(24 "In11.Cu" signal "L12")
		(26 "In12.Cu" signal "L13GND")
		(2 "B.Cu" signal "BOTTOM")
		(9 "F.Adhes" user "F.Adhesive")
		(11 "B.Adhes" user "B.Adhesive")
		(13 "F.Paste" user "Package Geometry/Pastemask Top")
		(15 "B.Paste" user "Package Geometry/Pastemask Bottom")
		(5 "F.SilkS" user "Ref Des/Silkscreen Top")
		(7 "B.SilkS" user "Ref Des/Silkscreen Bottom")
		(1 "F.Mask" user "Board Geometry/Soldermask Top")
		(3 "B.Mask" user "Board Geometry/Soldermask Bottom")
		(17 "Dwgs.User" user "User.Drawings")
		(19 "Cmts.User" user "User.Comments")
		(21 "Eco1.User" user "User.Eco1")
		(23 "Eco2.User" user "User.Eco2")
		(25 "Edge.Cuts" user "Board Geometry/Outline")
		(27 "Margin" user)
		(31 "F.CrtYd" user "Package Geometry/Place Bound Top")
		(29 "B.CrtYd" user "Package Geometry/Place Bound Bottom")
		(35 "F.Fab" user "Ref Des/Assembly Top")
		(33 "B.Fab" user "Ref Des/Assembly Bottom")
	)
	(footprint ""
		(layer "B.Cu")
		(at 345.919806 -61.257434)
		(property "Reference" "C2U12"
			(at 0 0 0)
			(layer "B.SilkS")
			(hide yes)
			(effects
				(font
					(size 1.27 1.27)
				)
				(justify mirror)
			)
		)
		(property "Value" ""
			(at 0 0 0)
			(layer "B.Fab")
			(effects
				(font
					(size 1.27 1.27)
				)
				(justify mirror)
			)
		)
		(duplicate_pad_numbers_are_jumpers no)
		(fp_poly
			(pts
				(xy -0.3048 -0.1016) (xy -0.3048 0.9906) (xy 0.3048 0.9906) (xy 0.3048 -0.1016)
			)
			(stroke
				(width 0)
				(type default)
			)
			(fill no)
			(layer "B.CrtYd")
		)
		(fp_line
			(start -0.3048 -0.1016)
			(end 0.3048 -0.1016)
			(stroke
				(width 0.1)
				(type default)
			)
			(layer "B.Fab")
		)
		(fp_line
			(start -0.3048 0.9906)
			(end -0.3048 -0.1016)
			(stroke
				(width 0.1)
				(type default)
			)
			(layer "B.Fab")
		)
		(fp_line
			(start 0.3048 -0.1016)
			(end 0.3048 0.9906)
			(stroke
				(width 0.1)
				(type default)
			)
			(layer "B.Fab")
		)
		(fp_line
			(start 0.3048 0.9906)
			(end -0.3048 0.9906)
			(stroke
				(width 0.1)
				(type default)
			)
			(layer "B.Fab")
		)
		(pad "1" smd rect
			(at 0 0 180)
			(size 0.508 0.508)
			(layers "B.Cu" "B.Mask" "B.Paste")
			(net "P3E_CPU0_PE1_PCH_RXN<4>")
		)
		(pad "2" smd rect
			(at 0 0.889 180)
			(size 0.508 0.508)
			(layers "B.Cu" "B.Mask" "B.Paste")
			(net "P3E_CPU0_PE1_SS_RXN<4>")
		)
		(zone
			(layer "B.Cu")
			(hatch none 0.5)
			(connect_pads
				(clearance 0)
			)
			(min_thickness 0.25)
			(keepout
				(tracks allowed)
				(vias not_allowed)
				(pads allowed)
				(copperpour not_allowed)
				(footprints allowed)
			)
			(placement
				(enabled no)
				(sheetname "")
			)
			(fill
				(thermal_gap 0.5)
				(thermal_bridge_width 0.5)
				(island_removal_mode 0)
			)
			(polygon
				(pts
					(xy 346.173806 -61.003434) (xy 345.665806 -61.003434) (xy 345.665806 -60.622434) (xy 346.173806 -60.622434)
				)
			)
		)
	)
	(footprint ""
		(layer "B.Cu")
		(at 171.1706 -147.8026 90)
		(property "Reference" "R6L6"
			(at 0 0 90)
			(layer "B.SilkS")
			(hide yes)
			(effects
				(font
					(size 1.27 1.27)
				)
				(justify mirror)
			)
		)
		(property "Value" ""
			(at 0 0 90)
			(layer "B.Fab")
			(effects
				(font
					(size 1.27 1.27)
				)
				(justify mirror)
			)
		)
		(duplicate_pad_numbers_are_jumpers no)
		(fp_rect
			(start 0.2794 0.9906)
			(end -0.2794 -0.1016)
			(stroke
				(width 0)
				(type default)
			)
			(fill no)
			(layer "B.CrtYd")
		)
		(fp_line
			(start 0.2794 -0.1016)
			(end 0.2794 0.9906)
			(stroke
				(width 0.1)
				(type default)
			)
			(layer "B.Fab")
		)
		(fp_line
			(start -0.2794 -0.1016)
			(end 0.2794 -0.1016)
			(stroke
				(width 0.1)
				(type default)
			)
			(layer "B.Fab")
		)
		(fp_line
			(start 0.2794 0.9906)
			(end -0.2794 0.9906)
			(stroke
				(width 0.1)
				(type default)
			)
			(layer "B.Fab")
		)
		(fp_line
			(start -0.2794 0.9906)
			(end -0.2794 -0.1016)
			(stroke
				(width 0.1)
				(type default)
			)
			(layer "B.Fab")
		)
		(pad "1" smd rect
			(at 0 0 270)
			(size 0.508 0.508)
			(layers "B.Cu" "B.Mask" "B.Paste")
			(net "PVDDQ_KLM")
		)
		(pad "2" smd rect
			(at 0 0.889 270)
			(size 0.508 0.508)
			(layers "B.Cu" "B.Mask" "B.Paste")
			(net "VSENSE_PVDDQ_KLM_VTT")
		)
		(zone
			(layer "B.Cu")
			(hatch none 0.5)
			(connect_pads
				(clearance 0)
			)
			(min_thickness 0.25)
			(keepout
				(tracks not_allowed)
				(vias allowed)
				(pads allowed)
				(copperpour not_allowed)
				(footprints allowed)
			)
			(placement
				(enabled no)
				(sheetname "")
			)
			(fill
				(thermal_gap 0.5)
				(thermal_bridge_width 0.5)
				(island_removal_mode 0)
			)
			(polygon
				(pts
					(xy 171.8056 -148.0566) (xy 171.4246 -148.0566) (xy 171.4246 -147.5486) (xy 171.8056 -147.5486)
				)
			)
		)
		(zone
			(layer "B.Cu")
			(hatch none 0.5)
			(connect_pads
				(clearance 0)
			)
			(min_thickness 0.25)
			(keepout
				(tracks allowed)
				(vias not_allowed)
				(pads allowed)
				(copperpour not_allowed)
				(footprints allowed)
			)
			(placement
				(enabled no)
				(sheetname "")
			)
			(fill
				(thermal_gap 0.5)
				(thermal_bridge_width 0.5)
				(island_removal_mode 0)
			)
			(polygon
				(pts
					(xy 171.8056 -148.0566) (xy 171.4246 -148.0566) (xy 171.4246 -147.5486) (xy 171.8056 -147.5486)
				)
			)
		)
	)
	(footprint ""
		(layer "B.Cu")
		(at 414.5534 -141.0208 -90)
		(property "Reference" "C2L47"
			(at 0 0 90)
			(layer "B.SilkS")
			(hide yes)
			(effects
				(font
					(size 1.27 1.27)
				)
				(justify mirror)
			)
		)
		(property "Value" ""
			(at 0 0 90)
			(layer "B.Fab")
			(effects
				(font
					(size 1.27 1.27)
				)
				(justify mirror)
			)
		)
		(duplicate_pad_numbers_are_jumpers no)
		(fp_poly
			(pts
				(xy -0.3048 -0.1016) (xy -0.3048 0.9906) (xy 0.3048 0.9906) (xy 0.3048 -0.1016)
			)
			(stroke
				(width 0)
				(type default)
			)
			(fill no)
			(layer "B.CrtYd")
		)
		(fp_line
			(start -0.3048 0.9906)
			(end -0.3048 -0.1016)
			(stroke
				(width 0.1)
				(type default)
			)
			(layer "B.Fab")
		)
		(fp_line
			(start 0.3048 0.9906)
			(end -0.3048 0.9906)
			(stroke
				(width 0.1)
				(type default)
			)
			(layer "B.Fab")
		)
		(fp_line
			(start -0.3048 -0.1016)
			(end 0.3048 -0.1016)
			(stroke
				(width 0.1)
				(type default)
			)
			(layer "B.Fab")
		)
		(fp_line
			(start 0.3048 -0.1016)
			(end 0.3048 0.9906)
			(stroke
				(width 0.1)
				(type default)
			)
			(layer "B.Fab")
		)
		(pad "1" smd rect
			(at 0 0 90)
			(size 0.508 0.508)
			(layers "B.Cu" "B.Mask" "B.Paste")
			(net "SATA6G_P4_TX_C_DP")
		)
		(pad "2" smd rect
			(at 0 0.889 90)
			(size 0.508 0.508)
			(layers "B.Cu" "B.Mask" "B.Paste")
			(net "SATA6G_PCH_PCIE_UP_SATA_TXP<4>")
		)
		(zone
			(layer "B.Cu")
			(hatch none 0.5)
			(connect_pads
				(clearance 0)
			)
			(min_thickness 0.25)
			(keepout
				(tracks not_allowed)
				(vias allowed)
				(pads allowed)
				(copperpour not_allowed)
				(footprints allowed)
			)
			(placement
				(enabled no)
				(sheetname "")
			)
			(fill
				(thermal_gap 0.5)
				(thermal_bridge_width 0.5)
				(island_removal_mode 0)
			)
			(polygon
				(pts
					(xy 413.9184 -140.7668) (xy 413.9184 -141.2748) (xy 414.2994 -141.2748) (xy 414.2994 -140.7668)
				)
			)
		)
		(zone
			(layer "B.Cu")
			(hatch none 0.5)
			(connect_pads
				(clearance 0)
			)
			(min_thickness 0.25)
			(keepout
				(tracks allowed)
				(vias not_allowed)
				(pads allowed)
				(copperpour not_allowed)
				(footprints allowed)
			)
			(placement
				(enabled no)
				(sheetname "")
			)
			(fill
				(thermal_gap 0.5)
				(thermal_bridge_width 0.5)
				(island_removal_mode 0)
			)
			(polygon
				(pts
					(xy 414.2994 -140.7668) (xy 414.2994 -141.2748) (xy 413.9184 -141.2748) (xy 413.9184 -140.7668)
				)
			)
		)
	)
	(footprint ""
		(layer "B.Cu")
		(at 63.246 -64.7954 180)
		(property "Reference" "R1E4"
			(at 0 0 0)
			(layer "B.SilkS")
			(hide yes)
			(effects
				(font
					(size 1.27 1.27)
				)
				(justify mirror)
			)
		)
		(property "Value" ""
			(at 0 0 0)
			(layer "B.Fab")
			(effects
				(font
					(size 1.27 1.27)
				)
				(justify mirror)
			)
		)
		(duplicate_pad_numbers_are_jumpers no)
		(fp_poly
			(pts
				(xy 0.2794 -0.1016) (xy -0.2794 -0.1016) (xy -0.2794 0.9906) (xy 0.2794 0.9906)
			)
			(stroke
				(width 0)
				(type default)
			)
			(fill no)
			(layer "B.CrtYd")
		)
		(fp_line
			(start 0.2794 0.9906)
			(end -0.2794 0.9906)
			(stroke
				(width 0.1)
				(type default)
			)
			(layer "B.Fab")
		)
		(fp_line
			(start 0.2794 -0.1016)
			(end 0.2794 0.9906)
			(stroke
				(width 0.1)
				(type default)
			)
			(layer "B.Fab")
		)
		(fp_line
			(start -0.2794 0.9906)
			(end -0.2794 -0.1016)
			(stroke
				(width 0.1)
				(type default)
			)
			(layer "B.Fab")
		)
		(fp_line
			(start -0.2794 -0.1016)
			(end 0.2794 -0.1016)
			(stroke
				(width 0.1)
				(type default)
			)
			(layer "B.Fab")
		)
		(pad "1" smd rect
			(at 0 0)
			(size 0.508 0.508)
			(layers "B.Cu" "B.Mask" "B.Paste")
			(net "VSENSE_PVCCIN_CPU1_P")
		)
		(pad "2" smd rect
			(at 0 0.889)
			(size 0.508 0.508)
			(layers "B.Cu" "B.Mask" "B.Paste")
			(net "PVCCIN_CPU1")
		)
		(zone
			(layer "B.Cu")
			(hatch none 0.5)
			(connect_pads
				(clearance 0)
			)
			(min_thickness 0.25)
			(keepout
				(tracks not_allowed)
				(vias allowed)
				(pads allowed)
				(copperpour not_allowed)
				(footprints allowed)
			)
			(placement
				(enabled no)
				(sheetname "")
			)
			(fill
				(thermal_gap 0.5)
				(thermal_bridge_width 0.5)
				(island_removal_mode 0)
			)
			(polygon
				(pts
					(xy 62.992 -65.4304) (xy 63.5 -65.4304) (xy 63.5 -65.0494) (xy 62.992 -65.0494)
				)
			)
		)
		(zone
			(layer "B.Cu")
			(hatch none 0.5)
			(connect_pads
				(clearance 0)
			)
			(min_thickness 0.25)
			(keepout
				(tracks allowed)
				(vias not_allowed)
				(pads allowed)
				(copperpour not_allowed)
				(footprints allowed)
			)
			(placement
				(enabled no)
				(sheetname "")
			)
			(fill
				(thermal_gap 0.5)
				(thermal_bridge_width 0.5)
				(island_removal_mode 0)
			)
			(polygon
				(pts
					(xy 62.992 -65.0494) (xy 63.5 -65.0494) (xy 63.5 -65.4304) (xy 62.992 -65.4304)
				)
			)
		)
	)
	(footprint ""
		(layer "B.Cu")
		(at 350.022414 -126.345442 -90)
		(property "Reference" "C3M11"
			(at 0 0 90)
			(layer "B.SilkS")
			(hide yes)
			(effects
				(font
					(size 1.27 1.27)
				)
				(justify mirror)
			)
		)
		(property "Value" ""
			(at 0 0 90)
			(layer "B.Fab")
			(effects
				(font
					(size 1.27 1.27)
				)
				(justify mirror)
			)
		)
		(duplicate_pad_numbers_are_jumpers no)
		(fp_poly
			(pts
				(xy -0.3048 -0.1016) (xy -0.3048 0.9906) (xy 0.3048 0.9906) (xy 0.3048 -0.1016)
			)
			(stroke
				(width 0)
				(type default)
			)
			(fill no)
			(layer "B.CrtYd")
		)
		(fp_line
			(start -0.3048 0.9906)
			(end -0.3048 -0.1016)
			(stroke
				(width 0.1)
				(type default)
			)
			(layer "B.Fab")
		)
		(fp_line
			(start 0.3048 0.9906)
			(end -0.3048 0.9906)
			(stroke
				(width 0.1)
				(type default)
			)
			(layer "B.Fab")
		)
		(fp_line
			(start -0.3048 -0.1016)
			(end 0.3048 -0.1016)
			(stroke
				(width 0.1)
				(type default)
			)
			(layer "B.Fab")
		)
		(fp_line
			(start 0.3048 -0.1016)
			(end 0.3048 0.9906)
			(stroke
				(width 0.1)
				(type default)
			)
			(layer "B.Fab")
		)
		(pad "1" smd rect
			(at 0 0 90)
			(size 0.508 0.508)
			(layers "B.Cu" "B.Mask" "B.Paste")
			(net "P3E_CPU0_PE1_PCH_R_RXP<14>")
		)
		(pad "2" smd rect
			(at 0 0.889 90)
			(size 0.508 0.508)
			(layers "B.Cu" "B.Mask" "B.Paste")
			(net "P3E_CPU0_PE1_PCH_RXP<14>")
		)
		(zone
			(layer "B.Cu")
			(hatch none 0.5)
			(connect_pads
				(clearance 0)
			)
			(min_thickness 0.25)
			(keepout
				(tracks not_allowed)
				(vias allowed)
				(pads allowed)
				(copperpour not_allowed)
				(footprints allowed)
			)
			(placement
				(enabled no)
				(sheetname "")
			)
			(fill
				(thermal_gap 0.5)
				(thermal_bridge_width 0.5)
				(island_removal_mode 0)
			)
			(polygon
				(pts
					(xy 349.387414 -126.091442) (xy 349.387414 -126.599442) (xy 349.768414 -126.599442) (xy 349.768414 -126.091442)
				)
			)
		)
		(zone
			(layer "B.Cu")
			(hatch none 0.5)
			(connect_pads
				(clearance 0)
			)
			(min_thickness 0.25)
			(keepout
				(tracks allowed)
				(vias not_allowed)
				(pads allowed)
				(copperpour not_allowed)
				(footprints allowed)
			)
			(placement
				(enabled no)
				(sheetname "")
			)
			(fill
				(thermal_gap 0.5)
				(thermal_bridge_width 0.5)
				(island_removal_mode 0)
			)
			(polygon
				(pts
					(xy 349.768414 -126.091442) (xy 349.768414 -126.599442) (xy 349.387414 -126.599442) (xy 349.387414 -126.091442)
				)
			)
		)
	)
	(footprint ""
		(layer "B.Cu")
		(at 112.378236 -68.603114 -90)
		(property "Reference" "R7P22"
			(at 0 0 90)
			(layer "B.SilkS")
			(hide yes)
			(effects
				(font
					(size 1.27 1.27)
				)
				(justify mirror)
			)
		)
		(property "Value" ""
			(at 0 0 90)
			(layer "B.Fab")
			(effects
				(font
					(size 1.27 1.27)
				)
				(justify mirror)
			)
		)
		(duplicate_pad_numbers_are_jumpers no)
		(fp_poly
			(pts
				(xy 0.2794 -0.1016) (xy -0.2794 -0.1016) (xy -0.2794 0.9906) (xy 0.2794 0.9906)
			)
			(stroke
				(width 0)
				(type default)
			)
			(fill no)
			(layer "B.CrtYd")
		)
		(fp_line
			(start -0.2794 0.9906)
			(end -0.2794 -0.1016)
			(stroke
				(width 0.1)
				(type default)
			)
			(layer "B.Fab")
		)
		(fp_line
			(start 0.2794 0.9906)
			(end -0.2794 0.9906)
			(stroke
				(width 0.1)
				(type default)
			)
			(layer "B.Fab")
		)
		(fp_line
			(start -0.2794 -0.1016)
			(end 0.2794 -0.1016)
			(stroke
				(width 0.1)
				(type default)
			)
			(layer "B.Fab")
		)
		(fp_line
			(start 0.2794 -0.1016)
			(end 0.2794 0.9906)
			(stroke
				(width 0.1)
				(type default)
			)
			(layer "B.Fab")
		)
		(pad "1" smd rect
			(at 0 0 90)
			(size 0.508 0.508)
			(layers "B.Cu" "B.Mask" "B.Paste")
			(net "PVCCIO_CPU1")
		)
		(pad "2" smd rect
			(at 0 0.889 90)
			(size 0.508 0.508)
			(layers "B.Cu" "B.Mask" "B.Paste")
			(net "PU_CPU1_LEGACY_SKT")
		)
		(zone
			(layer "B.Cu")
			(hatch none 0.5)
			(connect_pads
				(clearance 0)
			)
			(min_thickness 0.25)
			(keepout
				(tracks not_allowed)
				(vias allowed)
				(pads allowed)
				(copperpour not_allowed)
				(footprints allowed)
			)
			(placement
				(enabled no)
				(sheetname "")
			)
			(fill
				(thermal_gap 0.5)
				(thermal_bridge_width 0.5)
				(island_removal_mode 0)
			)
			(polygon
				(pts
					(xy 111.743236 -68.349114) (xy 111.743236 -68.857114) (xy 112.124236 -68.857114) (xy 112.124236 -68.349114)
				)
			)
		)
		(zone
			(layer "B.Cu")
			(hatch none 0.5)
			(connect_pads
				(clearance 0)
			)
			(min_thickness 0.25)
			(keepout
				(tracks allowed)
				(vias not_allowed)
				(pads allowed)
				(copperpour not_allowed)
				(footprints allowed)
			)
			(placement
				(enabled no)
				(sheetname "")
			)
			(fill
				(thermal_gap 0.5)
				(thermal_bridge_width 0.5)
				(island_removal_mode 0)
			)
			(polygon
				(pts
					(xy 112.124236 -68.349114) (xy 112.124236 -68.857114) (xy 111.743236 -68.857114) (xy 111.743236 -68.349114)
				)
			)
		)
	)
	(footprint ""
		(layer "B.Cu")
		(at 406.4 -105.8545 180)
		(property "Reference" "C2N21"
			(at 0 0 0)
			(layer "B.SilkS")
			(hide yes)
			(effects
				(font
					(size 1.27 1.27)
				)
				(justify mirror)
			)
		)
		(property "Value" ""
			(at 0 0 0)
			(layer "B.Fab")
			(effects
				(font
					(size 1.27 1.27)
				)
				(justify mirror)
			)
		)
		(duplicate_pad_numbers_are_jumpers no)
		(fp_poly
			(pts
				(xy 0.4953 -0.2032) (xy -0.4953 -0.2032) (xy -0.4953 1.6002) (xy 0.4953 1.6002)
			)
			(stroke
				(width 0)
				(type default)
			)
			(fill no)
			(layer "B.CrtYd")
		)
		(fp_line
			(start 0.4953 1.6002)
			(end 0.4953 -0.2032)
			(stroke
				(width 0.1)
				(type default)
			)
			(layer "B.Fab")
		)
		(fp_line
			(start 0.4953 -0.2032)
			(end -0.4953 -0.2032)
			(stroke
				(width 0.1)
				(type default)
			)
			(layer "B.Fab")
		)
		(fp_line
			(start -0.4953 1.6002)
			(end 0.4953 1.6002)
			(stroke
				(width 0.1)
				(type default)
			)
			(layer "B.Fab")
		)
		(fp_line
			(start -0.4953 -0.2032)
			(end -0.4953 1.6002)
			(stroke
				(width 0.1)
				(type default)
			)
			(layer "B.Fab")
		)
		(pad "1" smd rect
			(at 0 0)
			(size 0.762 0.889)
			(layers "B.Cu" "B.Mask" "B.Paste")
			(net "P3V3_STBY")
		)
		(pad "2" smd rect
			(at 0 1.397)
			(size 0.762 0.889)
			(layers "B.Cu" "B.Mask" "B.Paste")
			(net "GND")
		)
		(zone
			(layer "B.Cu")
			(hatch none 0.5)
			(connect_pads
				(clearance 0)
			)
			(min_thickness 0.25)
			(keepout
				(tracks not_allowed)
				(vias allowed)
				(pads allowed)
				(copperpour not_allowed)
				(footprints allowed)
			)
			(placement
				(enabled no)
				(sheetname "")
			)
			(fill
				(thermal_gap 0.5)
				(thermal_bridge_width 0.5)
				(island_removal_mode 0)
			)
			(polygon
				(pts
					(xy 406.019 -106.299) (xy 406.781 -106.299) (xy 406.781 -106.807) (xy 406.019 -106.807)
				)
			)
		)
	)
	(footprint ""
		(layer "B.Cu")
		(at 267.946886 -68.17614 180)
		(property "Reference" "C5P44"
			(at 0 0 0)
			(layer "B.SilkS")
			(hide yes)
			(effects
				(font
					(size 1.27 1.27)
				)
				(justify mirror)
			)
		)
		(property "Value" ""
			(at 0 0 0)
			(layer "B.Fab")
			(effects
				(font
					(size 1.27 1.27)
				)
				(justify mirror)
			)
		)
		(duplicate_pad_numbers_are_jumpers no)
		(fp_poly
			(pts
				(xy 0.7239 -0.2159) (xy -0.7239 -0.2159) (xy -0.7239 1.9939) (xy 0.7239 1.9939)
			)
			(stroke
				(width 0)
				(type default)
			)
			(fill no)
			(layer "B.CrtYd")
		)
		(fp_line
			(start 0.7239 1.9939)
			(end -0.7239 1.9939)
			(stroke
				(width 0.1)
				(type default)
			)
			(layer "B.Fab")
		)
		(fp_line
			(start 0.7239 -0.2159)
			(end 0.7239 1.9939)
			(stroke
				(width 0.1)
				(type default)
			)
			(layer "B.Fab")
		)
		(fp_line
			(start -0.7239 1.9939)
			(end -0.7239 -0.2159)
			(stroke
				(width 0.1)
				(type default)
			)
			(layer "B.Fab")
		)
		(fp_line
			(start -0.7239 -0.2159)
			(end 0.7239 -0.2159)
			(stroke
				(width 0.1)
				(type default)
			)
			(layer "B.Fab")
		)
		(pad "1" smd rect
			(at 0 0)
			(size 1.27 1.016)
			(layers "B.Cu" "B.Mask" "B.Paste")
			(net "PVDDQ_ABC")
		)
		(pad "2" smd rect
			(at 0 1.778)
			(size 1.27 1.016)
			(layers "B.Cu" "B.Mask" "B.Paste")
			(net "GND")
		)
		(zone
			(layer "B.Cu")
			(hatch none 0.5)
			(connect_pads
				(clearance 0)
			)
			(min_thickness 0.25)
			(keepout
				(tracks not_allowed)
				(vias allowed)
				(pads allowed)
				(copperpour not_allowed)
				(footprints allowed)
			)
			(placement
				(enabled no)
				(sheetname "")
			)
			(fill
				(thermal_gap 0.5)
				(thermal_bridge_width 0.5)
				(island_removal_mode 0)
			)
			(polygon
				(pts
					(xy 267.311886 -68.68414) (xy 268.581886 -68.68414) (xy 268.581886 -69.44614) (xy 267.311886 -69.44614)
				)
			)
		)
	)
)
